M48
;Layer_Color=9474304
;FILE_FORMAT=2:5
INCH,LZ
;TYPE=PLATED
T04F00S00C0.02362
T05F00S00C0.02559
;TYPE=NON_PLATED
%
G90
G05
T04
G00X0621457Y-0296457
M15
G01X0618701
M16
G00X0621457Y-0263583
M15
G01X0618701
M16
T05
G00X0608661Y-0288779
M15
G01X0607874
M16
G00X0608661Y-027126
M15
G01X0607874
M16
M17
M30
